# BASEBOARD_FAB2 (Tioga Pass) — schematic netlist excerpt (pin names and nets, part order shuffled) for the footprints in the layout excerpt that follows; sources: Cadence DE-HDL packaged netlist, KiCad conversion of Wiwynn_Tioga_Pass_MB.brd

J9B4  SCONN10_C12536004  CONN  pkg SMLF  page 113
  IO1  = JTAG_MCP_TCK_R
  IO2  = GND
  IO3  = JTAG_MCP_MUX_TDO
  IO4  = P1V8_MCP_CPU0
  IO5  = JTAG_MCP_TMS_R
  IO6  = JTAG_MCP_TRST_N
  IO7  = PWRGD_CPU0_G_R
  IO8  = TP_JTAG_MCP_IO8_RSVD
  IO9  = JTAG_MCP_MUX_TDI
  IO10  = GND

(kicad_pcb
	(version 20260206)
	(generator "pcbnew")
	(generator_version "10.0")
	(general
		(thickness 1.6)
		(legacy_teardrops no)
	)
	(paper "A4")
	(title_block
		(title "Wiwynn_Tioga_Pass_MB.brd")
		(comment 1 "Tioga Pass / footprint 1602 of 4770 (J9B4), pads 1-12 of 12")
	)
	(layers
		(0 "F.Cu" signal "TOP")
		(4 "In1.Cu" signal "L2GND")
		(6 "In2.Cu" signal "L3")
		(8 "In3.Cu" signal "L4GND")
		(10 "In4.Cu" signal "L5")
		(12 "In5.Cu" signal "L6GND")
		(14 "In6.Cu" signal "L7VCC")
		(16 "In7.Cu" signal "L8VCC")
		(18 "In8.Cu" signal "L9GND")
		(20 "In9.Cu" signal "L10")
		(22 "In10.Cu" signal "L11GND")
		(24 "In11.Cu" signal "L12")
		(26 "In12.Cu" signal "L13GND")
		(2 "B.Cu" signal "BOTTOM")
		(9 "F.Adhes" user "F.Adhesive")
		(11 "B.Adhes" user "B.Adhesive")
		(13 "F.Paste" user "Package Geometry/Pastemask Top")
		(15 "B.Paste" user "Package Geometry/Pastemask Bottom")
		(5 "F.SilkS" user "Ref Des/Silkscreen Top")
		(7 "B.SilkS" user "Ref Des/Silkscreen Bottom")
		(1 "F.Mask" user "Board Geometry/Soldermask Top")
		(3 "B.Mask" user "Board Geometry/Soldermask Bottom")
		(17 "Dwgs.User" user "User.Drawings")
		(19 "Cmts.User" user "User.Comments")
		(21 "Eco1.User" user "User.Eco1")
		(23 "Eco2.User" user "User.Eco2")
		(25 "Edge.Cuts" user "Board Geometry/Outline")
		(27 "Margin" user)
		(31 "F.CrtYd" user "Package Geometry/Place Bound Top")
		(29 "B.CrtYd" user "Package Geometry/Place Bound Bottom")
		(35 "F.Fab" user "Ref Des/Assembly Top")
		(33 "B.Fab" user "Ref Des/Assembly Bottom")
	)
	(footprint ""
		(layer "F.Cu")
		(at 470.282016 -134.366)
		(property "Reference" "J9B4"
			(at -4.77012 9.83615 0)
			(unlocked yes)
			(layer "F.SilkS")
			(effects
				(font
					(size 0.7874 0.5842)
					(thickness 0.1524)
				)
				(justify left)
			)
		)
		(property "Value" ""
			(at 0 0 0)
			(layer "F.Fab")
			(effects
				(font
					(size 1.27 1.27)
				)
			)
		)
		(duplicate_pad_numbers_are_jumpers no)
		(pad "" np_thru_hole circle
			(at 2.1209 0.999998)
			(size 0.254 0.254)
			(drill 1.016)
			(layers "*.Cu" "*.Mask")
			(clearance 0.6985)
			(thermal_gap 0.6985)
		)
		(pad "" np_thru_hole circle
			(at 2.1209 6.999986)
			(size 0.254 0.254)
			(drill 1.016)
			(layers "*.Cu" "*.Mask")
			(clearance 0.6985)
			(thermal_gap 0.6985)
		)
		(pad "1" smd rect
			(at 0 0)
			(size 2.7432 1.016)
			(layers "F.Cu" "F.Mask" "F.Paste")
			(net "JTAG_MCP_TCK_R")
		)
		(pad "2" smd rect
			(at 4.2418 0)
			(size 2.7432 1.016)
			(layers "F.Cu" "F.Mask" "F.Paste")
			(net "GND")
		)
		(pad "3" smd rect
			(at 0 1.999996)
			(size 2.7432 1.016)
			(layers "F.Cu" "F.Mask" "F.Paste")
			(net "JTAG_MCP_MUX_TDO")
		)
		(pad "4" smd rect
			(at 4.2418 1.999996)
			(size 2.7432 1.016)
			(layers "F.Cu" "F.Mask" "F.Paste")
			(net "P1V8_MCP_CPU0")
		)
		(pad "5" smd rect
			(at 0 3.999992)
			(size 2.7432 1.016)
			(layers "F.Cu" "F.Mask" "F.Paste")
			(net "JTAG_MCP_TMS_R")
		)
		(pad "6" smd rect
			(at 4.2418 3.999992)
			(size 2.7432 1.016)
			(layers "F.Cu" "F.Mask" "F.Paste")
			(net "JTAG_MCP_TRST_N")
		)
		(pad "7" smd rect
			(at 0 5.999988)
			(size 2.7432 1.016)
			(layers "F.Cu" "F.Mask" "F.Paste")
			(net "PWRGD_CPU0_G_R")
		)
		(pad "8" smd rect
			(at 4.2418 5.999988)
			(size 2.7432 1.016)
			(layers "F.Cu" "F.Mask" "F.Paste")
			(net "TP_JTAG_MCP_IO8_RSVD")
		)
		(pad "9" smd rect
			(at 0 7.999984)
			(size 2.7432 1.016)
			(layers "F.Cu" "F.Mask" "F.Paste")
			(net "JTAG_MCP_MUX_TDI")
		)
		(pad "10" smd rect
			(at 4.2418 7.999984)
			(size 2.7432 1.016)
			(layers "F.Cu" "F.Mask" "F.Paste")
			(net "GND")
		)
	)
)
